# S9S_MB_2U (Grand Teton) — schematic parts with pin connectivity, parts 1909–2062 of 6093; source: Cadence DE-HDL packaged netlist (pstxprt.dat, pstxnet.dat, pstchip.dat)

PC412_P1_1  Q_CAP  22UF 4V 20% X6S  pkg C0805  page 289 : 1 = PVCCFA_EHV_FIVRA_CPU1 ; 2 = GND
PC413_P1_2  Q_CAP  22UF 4V 20% X6S  pkg C0805  page 289 : 1 = PVCCFA_EHV_FIVRA_CPU1 ; 2 = GND
PC414  Q_CAPP  560UF 2.5V 20% OSCON  pkg THLF  page 289 : 1 = PVCCFA_EHV_FIVRA_CPU1 ; 2 = GND
PC415  Q_CAPP  560UF 2.5V 20% OSCON  pkg THLF  page 289 : 1 = PVCCFA_EHV_FIVRA_CPU1 ; 2 = GND
PC416  Q_CAPP  560UF 2.5V 20% OSCON  pkg THLF  page 289 : 1 = PVCCFA_EHV_FIVRA_CPU1 ; 2 = GND
PC417  Q_CAPP  270UF 16V 20% OSCON  pkg THLF  page 289 : 1 = SW_P12V_PVCCFA_EHV_FIVRA_CPU1_L ; 2 = GND
PC418  Q_CAPP  330UF 2.5V +10/-35% SPCAP  pkg SMLF  page 289 : 1 = PVCCFA_EHV_FIVRA_CPU1 ; 2 = GND
PC422  Q_CAP  3300PF 50V 10% X7R  pkg 0402  page 284 : 1 = SH_PVCCFA_EHV_FIVRA_CPU1_R ; 2 = VSENSE_PVCCFA_EHV_FIVRA_CPU1_DN
PC428  Q_CAP  2.2UF 10V 10% X6S  pkg C0402  page 294 : 1 = PVCCFA_EHV_CPU1_VDD1 ; 2 = GND
PC429  Q_CAP  3300PF 50V 10% X7R  pkg 0402  page 294 : 1 = SW_P12V_PVCCINFAON_CPU1_FLT ; 2 = GND
PC430  Q_CAP  1UF 16V 10% X6S  pkg C0402  page 294 : 1 = SW_P12V_PVCCINFAON_CPU1_FLT ; 2 = GND
PC431  Q_CAP  100NF 50V 10% X7R  pkg C0402  page 294 : 1 = SW_PVCCFA_EHV_CPU1_BOOT1_R ; 2 = SW_PVCCFA_EHV_CPU1_BOOTR1
PC432  Q_CAP  22UF 16V 20% X6S  pkg C0805  page 294 : 1 = SW_P12V_PVCCINFAON_CPU1_FLT ; 2 = GND
PC433  Q_CAP  22UF 16V 20% X6S  pkg C0805  page 294 : 1 = SW_P12V_PVCCINFAON_CPU1_FLT ; 2 = GND
PC434  Q_CAP  100NF 50V 10% X7R  pkg C0402  page 294 : 1 = PVCCFA_EHV_CPU1 ; 2 = GND
PC435  Q_CAP  22UF 4V 20% X6S  pkg C0805  page 294 : 1 = PVCCFA_EHV_CPU1 ; 2 = GND
PC437  Q_CAP  22UF 4V 20% X6S  pkg C0805  page 294 : 1 = PVCCFA_EHV_CPU1 ; 2 = GND
PC440  Q_CAP  2.2UF 10V 10% X6S  pkg C0402  page 293 : 1 = PVCCINFAON_CPU1_VDD1 ; 2 = GND
PC441  Q_CAP  2.2UF 10V 10% X6S  pkg C0402  page 293 : 1 = PVCCINFAON_CPU1_VDD2 ; 2 = GND
PC442_P1_1  Q_CAP  3300PF 50V 10% X7R  pkg 0402  page 293 : 1 = SW_P12V_PVCCINFAON_CPU1_FLT ; 2 = GND
PC443_P1_2  Q_CAP  3300PF 50V 10% X7R  pkg 0402  page 293 : 1 = SW_P12V_PVCCINFAON_CPU1_FLT ; 2 = GND
PC444_P1_1  Q_CAP  1UF 16V 10% X6S  pkg C0402  page 293 : 1 = SW_P12V_PVCCINFAON_CPU1_FLT ; 2 = GND
PC445_P1_2  Q_CAP  1UF 16V 10% X6S  pkg C0402  page 293 : 1 = SW_P12V_PVCCINFAON_CPU1_FLT ; 2 = GND
PC446  Q_CAP  100NF 50V 10% X7R  pkg C0402  page 293 : 1 = SW_PVCCINFAON_CPU1_BOOT1_R ; 2 = SW_PVCCINFAON_CPU1_BOOTR1
PC447  Q_CAP  100NF 50V 10% X7R  pkg C0402  page 293 : 1 = SW_PVCCINFAON_CPU1_BOOT2_R ; 2 = SW_PVCCINFAON_CPU1_BOOTR2
PC448_P1_1  Q_CAP  22UF 16V 20% X6S  pkg C0805  page 293 : 1 = SW_P12V_PVCCINFAON_CPU1_FLT ; 2 = GND
PC449_P1_2  Q_CAP  22UF 16V 20% X6S  pkg C0805  page 293 : 1 = SW_P12V_PVCCINFAON_CPU1_FLT ; 2 = GND
PC450_P1_1  Q_CAP  22UF 16V 20% X6S  pkg C0805  page 293 : 1 = SW_P12V_PVCCINFAON_CPU1_FLT ; 2 = GND
PC451_P1_2  Q_CAP  22UF 16V 20% X6S  pkg C0805  page 293 : 1 = SW_P12V_PVCCINFAON_CPU1_FLT ; 2 = GND
PC452_P1_1  Q_CAP  100NF 50V 10% X7R  pkg C0402  page 293 : 1 = PVCCINFAON_CPU1 ; 2 = GND
PC455_P1_1  Q_CAP  22UF 4V 20% X6S  pkg C0805  page 293 : 1 = PVCCINFAON_CPU1 ; 2 = GND
PC456_P1_2  Q_CAP  22UF 4V 20% X6S  pkg C0805  page 293 : 1 = PVCCINFAON_CPU1 ; 2 = GND
PC457_P1_1  Q_CAP  22UF 4V 20% X6S  pkg C0805  page 293 : 1 = PVCCINFAON_CPU1 ; 2 = GND
PC458_P1_2  Q_CAP  22UF 4V 20% X6S  pkg C0805  page 293 : 1 = PVCCINFAON_CPU1 ; 2 = GND
PC460  Q_CAPP  270UF 16V 20% OSCON  pkg THLF  page 293 : 1 = SW_P12V_PVCCINFAON_CPU1_FLT ; 2 = GND
PC461  Q_CAPP  270UF 16V 20% OSCON  pkg THLF  page 293 : 1 = SW_P12V_PVCCINFAON_CPU1_FLT ; 2 = GND
PC467  Q_CAP  0.1UF 25V 10% EMPTY  pkg 0402  page 292 : 1 = PVCCINFAON_CPU1_CSPIN ; 2 = GND
PC468  Q_CAP  3300PF 50V 10% X7R  pkg 0402  page 292 : 1 = SH_PVCCINFAON_CPU1_R ; 2 = VSENSE_PVCCINFAON_CPU1_DN
PC469  Q_CAP  3300PF 50V 10% X7R  pkg 0402  page 292 : 1 = SH_PVCCFA_EHV_CPU1_R ; 2 = VSENSE_PVCCFA_EHV_CPU1_DN
PC474  Q_CAP  0.1UF 25V 10% X7R  pkg 0402  page 292 : 1 = PVCCINFAON_CPU1_VIN_CSNIN ; 2 = GND
PC475  Q_CAP  470PF 50V 10% X7R  pkg 0402  page 292 : 1 = PVCCINFAON_CPU1_ATSEN ; 2 = GND
PC476  Q_CAP  100NF 50V 10% EMPTY  pkg C0402  page 292 : 1 = PVCCINFAON_CPU1_VCC ; 2 = GND
PC477  Q_CAP  10UF 6.3V 20% X6S  pkg C0402  page 292 : 1 = PVCCINFAON_CPU1_VREF ; 2 = GND
PC478  Q_CAP  1UF 16V 10% X6S  pkg C0402  page 292 : 1 = PVCCINFAON_CPU1_VCC ; 2 = GND
PC479  Q_CAP  2.2UF 10V 10% X6S  pkg C0402  page 288 : 1 = PVCCIN_CPU1_VDD8 ; 2 = GND
PC480  Q_CAP  2.2UF 10V 10% X6S  pkg C0402  page 288 : 1 = PVCCIN_CPU1_VDD7 ; 2 = GND
PC481_P1_8  Q_CAP  2.2UF 10V 10% X6S  pkg C0402  page 288 : 1 = PVCCIN_CPU1_PVCC ; 2 = GND
PC482_P1_7  Q_CAP  2.2UF 10V 10% X6S  pkg C0402  page 288 : 1 = PVCCIN_CPU1_PVCC ; 2 = GND
PC483_P1_8  Q_CAP  3300PF 50V 10% X7R  pkg 0402  page 288 : 1 = SW_P12V_PVCCIN_CPU1_FLT ; 2 = GND
PC484_P1_7  Q_CAP  3300PF 50V 10% X7R  pkg 0402  page 288 : 1 = SW_P12V_PVCCIN_CPU1_FLT ; 2 = GND
PC485_P1_8  Q_CAP  1UF 16V 10% X6S  pkg C0402  page 288 : 1 = SW_P12V_PVCCIN_CPU1_FLT ; 2 = GND
PC486_P1_7  Q_CAP  1UF 16V 10% X6S  pkg C0402  page 288 : 1 = SW_P12V_PVCCIN_CPU1_FLT ; 2 = GND
PC487  Q_CAP  100NF 50V 10% X7R  pkg C0402  page 288 : 1 = SW_PVCCIN_CPU1_BOOT8_R ; 2 = SW_PVCCIN_CPU1_BOOTR8
PC488  Q_CAP  100NF 50V 10% X7R  pkg C0402  page 288 : 1 = SW_PVCCIN_CPU1_BOOT7_R ; 2 = SW_PVCCIN_CPU1_BOOTR7
PC489_P1_8  Q_CAP  22UF 16V 20% X6S  pkg C0805  page 288 : 1 = SW_P12V_PVCCIN_CPU1_FLT ; 2 = GND
PC490_P1_7  Q_CAP  22UF 16V 20% X6S  pkg C0805  page 288 : 1 = SW_P12V_PVCCIN_CPU1_FLT ; 2 = GND
PC491_P1_8  Q_CAP  22UF 16V 20% X6S  pkg C0805  page 288 : 1 = SW_P12V_PVCCIN_CPU1_FLT ; 2 = GND
PC492_P1_7  Q_CAP  22UF 16V 20% X6S  pkg C0805  page 288 : 1 = SW_P12V_PVCCIN_CPU1_FLT ; 2 = GND
PC493_P1_8  Q_CAP  22UF 16V 20% X6S  pkg C0805  page 288 : 1 = SW_P12V_PVCCIN_CPU1_FLT ; 2 = GND
PC494_P1_7  Q_CAP  22UF 16V 20% X6S  pkg C0805  page 288 : 1 = SW_P12V_PVCCIN_CPU1_FLT ; 2 = GND
PC495_P1_8  Q_CAP  1UF 16V 10% X6S  pkg C0402  page 288 : 1 = PVCCIN_CPU1 ; 2 = GND
PC496_P1_7  Q_CAP  1UF 16V 10% X6S  pkg C0402  page 288 : 1 = PVCCIN_CPU1 ; 2 = GND
PC497_P1_8  Q_CAP  22UF 4V 20% X6S  pkg C0805  page 288 : 1 = PVCCIN_CPU1 ; 2 = GND
PC498_P1_7  Q_CAP  22UF 4V 20% X6S  pkg C0805  page 288 : 1 = PVCCIN_CPU1 ; 2 = GND
PC499_P1_8  Q_CAP  22UF 4V 20% X6S  pkg C0805  page 288 : 1 = PVCCIN_CPU1 ; 2 = GND
PC500_P1_7  Q_CAP  22UF 4V 20% X6S  pkg C0805  page 288 : 1 = PVCCIN_CPU1 ; 2 = GND
PC501  Q_CAP  2.2UF 10V 10% X6S  pkg C0402  page 287 : 1 = PVCCIN_CPU1_VDD6 ; 2 = GND
PC502  Q_CAP  2.2UF 10V 10% X6S  pkg C0402  page 287 : 1 = PVCCIN_CPU1_VDD5 ; 2 = GND
PC503_P1_6  Q_CAP  2.2UF 10V 10% X6S  pkg C0402  page 287 : 1 = PVCCIN_CPU1_PVCC ; 2 = GND
PC504_P1_5  Q_CAP  2.2UF 10V 10% X6S  pkg C0402  page 287 : 1 = PVCCIN_CPU1_PVCC ; 2 = GND
PC505_P1_6  Q_CAP  3300PF 50V 10% X7R  pkg 0402  page 287 : 1 = SW_P12V_PVCCIN_CPU1_FLT ; 2 = GND
PC506_P1_5  Q_CAP  3300PF 50V 10% X7R  pkg 0402  page 287 : 1 = SW_P12V_PVCCIN_CPU1_FLT ; 2 = GND
PC507_P1_6  Q_CAP  1UF 16V 10% X6S  pkg C0402  page 287 : 1 = SW_P12V_PVCCIN_CPU1_FLT ; 2 = GND
PC508_P1_5  Q_CAP  1UF 16V 10% X6S  pkg C0402  page 287 : 1 = SW_P12V_PVCCIN_CPU1_FLT ; 2 = GND
PC509  Q_CAP  100NF 50V 10% X7R  pkg C0402  page 287 : 1 = SW_PVCCIN_CPU1_BOOT6_R ; 2 = SW_PVCCIN_CPU1_BOOTR6
PC510  Q_CAP  100NF 50V 10% X7R  pkg C0402  page 287 : 1 = SW_PVCCIN_CPU1_BOOT5_R ; 2 = SW_PVCCIN_CPU1_BOOTR5
PC511_P1_6  Q_CAP  22UF 16V 20% X6S  pkg C0805  page 287 : 1 = SW_P12V_PVCCIN_CPU1_FLT ; 2 = GND
PC512_P1_5  Q_CAP  22UF 16V 20% X6S  pkg C0805  page 287 : 1 = SW_P12V_PVCCIN_CPU1_FLT ; 2 = GND
PC513_P1_6  Q_CAP  22UF 16V 20% X6S  pkg C0805  page 287 : 1 = SW_P12V_PVCCIN_CPU1_FLT ; 2 = GND
PC514_P1_5  Q_CAP  22UF 16V 20% X6S  pkg C0805  page 287 : 1 = SW_P12V_PVCCIN_CPU1_FLT ; 2 = GND
PC515_P1_6  Q_CAP  22UF 16V 20% X6S  pkg C0805  page 287 : 1 = SW_P12V_PVCCIN_CPU1_FLT ; 2 = GND
PC516_P1_5  Q_CAP  22UF 16V 20% X6S  pkg C0805  page 287 : 1 = SW_P12V_PVCCIN_CPU1_FLT ; 2 = GND
PC519_P1_6  Q_CAP  22UF 4V 20% X6S  pkg C0805  page 287 : 1 = PVCCIN_CPU1 ; 2 = GND
PC520_P1_5  Q_CAP  22UF 4V 20% X6S  pkg C0805  page 287 : 1 = PVCCIN_CPU1 ; 2 = GND
PC521_P1_6  Q_CAP  22UF 4V 20% X6S  pkg C0805  page 287 : 1 = PVCCIN_CPU1 ; 2 = GND
PC522_P1_5  Q_CAP  22UF 4V 20% X6S  pkg C0805  page 287 : 1 = PVCCIN_CPU1 ; 2 = GND
PC523  Q_CAP  2.2UF 10V 10% X6S  pkg C0402  page 286 : 1 = PVCCIN_CPU1_VDD4 ; 2 = GND
PC524  Q_CAP  2.2UF 10V 10% X6S  pkg C0402  page 286 : 1 = PVCCIN_CPU1_VDD3 ; 2 = GND
PC525_P1_4  Q_CAP  2.2UF 10V 10% X6S  pkg C0402  page 286 : 1 = PVCCIN_CPU1_PVCC ; 2 = GND
PC526_P1_3  Q_CAP  2.2UF 10V 10% X6S  pkg C0402  page 286 : 1 = PVCCIN_CPU1_PVCC ; 2 = GND
PC527_P1_4  Q_CAP  3300PF 50V 10% X7R  pkg 0402  page 286 : 1 = SW_P12V_PVCCIN_CPU1_FLT ; 2 = GND
PC528_P1_3  Q_CAP  3300PF 50V 10% X7R  pkg 0402  page 286 : 1 = SW_P12V_PVCCIN_CPU1_FLT ; 2 = GND
PC529_P1_4  Q_CAP  1UF 16V 10% X6S  pkg C0402  page 286 : 1 = SW_P12V_PVCCIN_CPU1_FLT ; 2 = GND
PC530_P1_3  Q_CAP  1UF 16V 10% X6S  pkg C0402  page 286 : 1 = SW_P12V_PVCCIN_CPU1_FLT ; 2 = GND
PC531  Q_CAP  100NF 50V 10% X7R  pkg C0402  page 286 : 1 = SW_PVCCIN_CPU1_BOOT4_R ; 2 = SW_PVCCIN_CPU1_BOOTR4
PC532  Q_CAP  100NF 50V 10% X7R  pkg C0402  page 286 : 1 = SW_PVCCIN_CPU1_BOOT3_R ; 2 = SW_PVCCIN_CPU1_BOOTR3
PC533_P1_4  Q_CAP  22UF 16V 20% X6S  pkg C0805  page 286 : 1 = SW_P12V_PVCCIN_CPU1_FLT ; 2 = GND
PC534_P1_3  Q_CAP  22UF 16V 20% X6S  pkg C0805  page 286 : 1 = SW_P12V_PVCCIN_CPU1_FLT ; 2 = GND
PC535_P1_4  Q_CAP  22UF 16V 20% X6S  pkg C0805  page 286 : 1 = SW_P12V_PVCCIN_CPU1_FLT ; 2 = GND
PC536_P1_3  Q_CAP  22UF 16V 20% X6S  pkg C0805  page 286 : 1 = SW_P12V_PVCCIN_CPU1_FLT ; 2 = GND
PC537_P1_4  Q_CAP  22UF 16V 20% X6S  pkg C0805  page 286 : 1 = SW_P12V_PVCCIN_CPU1_FLT ; 2 = GND
PC538_P1_3  Q_CAP  22UF 16V 20% X6S  pkg C0805  page 286 : 1 = SW_P12V_PVCCIN_CPU1_FLT ; 2 = GND
PC541_P1_4  Q_CAP  22UF 4V 20% X6S  pkg C0805  page 286 : 1 = PVCCIN_CPU1 ; 2 = GND
PC542_P1_3  Q_CAP  22UF 4V 20% X6S  pkg C0805  page 286 : 1 = PVCCIN_CPU1 ; 2 = GND
PC543_P1_4  Q_CAP  22UF 4V 20% X6S  pkg C0805  page 286 : 1 = PVCCIN_CPU1 ; 2 = GND
PC544_P1_3  Q_CAP  22UF 4V 20% X6S  pkg C0805  page 286 : 1 = PVCCIN_CPU1 ; 2 = GND
PC547  Q_CAP  0.1UF 25V 10% EMPTY  pkg 0402  page 284 : 1 = PVCCIN_CPU1_CSPIN ; 2 = GND
PC548  Q_CAP  0.1UF 25V 10% X7R  pkg 0402  page 284 : 1 = PVCCIN_CPU1_VIN_CSNIN ; 2 = GND
PC549  Q_CAP  3300PF 50V 10% X7R  pkg 0402  page 284 : 1 = SH_PVCCIN_CPU1_R ; 2 = VSENSE_PVCCIN_CPU1_DN
PC552  Q_CAP  100NF 50V 10% EMPTY  pkg C0402  page 284 : 1 = PVCCIN_CPU1_VCC ; 2 = GND
PC553  Q_CAP  10UF 6.3V 20% X6S  pkg C0402  page 284 : 1 = PVCCIN_CPU1_VREF ; 2 = GND
PC554  Q_CAP  470PF 50V 10% X7R  pkg 0402  page 284 : 1 = PVCCIN_CPU1_ATSEN ; 2 = GND
PC555  Q_CAP  1UF 16V 10% X6S  pkg C0402  page 284 : 1 = PVCCIN_CPU1_VCC ; 2 = GND
PC556  Q_CAP  2.2UF 10V 10% X6S  pkg C0402  page 285 : 1 = PVCCIN_CPU1_VDD2 ; 2 = GND
PC557  Q_CAP  2.2UF 10V 10% X6S  pkg C0402  page 285 : 1 = PVCCIN_CPU1_VDD1 ; 2 = GND
PC558_P1_2  Q_CAP  2.2UF 10V 10% X6S  pkg C0402  page 285 : 1 = PVCCIN_CPU1_PVCC ; 2 = GND
PC559_P1_1  Q_CAP  2.2UF 10V 10% X6S  pkg C0402  page 285 : 1 = PVCCIN_CPU1_PVCC ; 2 = GND
PC560_P1_2  Q_CAP  3300PF 50V 10% X7R  pkg 0402  page 285 : 1 = SW_P12V_PVCCIN_CPU1_FLT ; 2 = GND
PC561_P1_1  Q_CAP  3300PF 50V 10% X7R  pkg 0402  page 285 : 1 = SW_P12V_PVCCIN_CPU1_FLT ; 2 = GND
PC562_P1_2  Q_CAP  1UF 16V 10% X6S  pkg C0402  page 285 : 1 = SW_P12V_PVCCIN_CPU1_FLT ; 2 = GND
PC563_P1_1  Q_CAP  1UF 16V 10% X6S  pkg C0402  page 285 : 1 = SW_P12V_PVCCIN_CPU1_FLT ; 2 = GND
PC564  Q_CAP  100NF 50V 10% X7R  pkg C0402  page 285 : 1 = SW_PVCCIN_CPU1_BOOT2_R ; 2 = SW_PVCCIN_CPU1_BOOTR2
PC565  Q_CAP  100NF 50V 10% X7R  pkg C0402  page 285 : 1 = SW_PVCCIN_CPU1_BOOT1_R ; 2 = SW_PVCCIN_CPU1_BOOTR1
PC566  Q_CAPP  270UF 16V 20% OSCON  pkg THLF  page 259 : 1 = SW_P3V3_AUX_FLT ; 2 = GND
PC566_P1_2  Q_CAP  22UF 16V 20% X6S  pkg C0805  page 285 : 1 = SW_P12V_PVCCIN_CPU1_FLT ; 2 = GND
PC567  Q_CAP  22UF 16V 20% X6S  pkg C0805  page 259 : 1 = SW_P3V3_AUX_FLT ; 2 = GND
PC567_P1_1  Q_CAP  22UF 16V 20% X6S  pkg C0805  page 285 : 1 = SW_P12V_PVCCIN_CPU1_FLT ; 2 = GND
PC568  Q_CAP  0.22UF 25V 10% X7R  pkg C0402  page 259 : 1 = SW_P3V3_AUX_BOOTR ; 2 = SW_P3V3_AUX_BOOT_R
PC568_P1_2  Q_CAP  22UF 16V 20% X6S  pkg C0805  page 285 : 1 = SW_P12V_PVCCIN_CPU1_FLT ; 2 = GND
PC569  Q_CAP  220PF 50V 10% X7R  pkg 0402  page 259 : 1 = P3V3_AUX_FB ; 2 = P3V3_AUX
PC569_P1_1  Q_CAP  22UF 16V 20% X6S  pkg C0805  page 285 : 1 = SW_P12V_PVCCIN_CPU1_FLT ; 2 = GND
PC570  Q_CAP  22UF 16V 20% X6S  pkg C0805  page 259 : 1 = SW_P3V3_AUX_FLT ; 2 = GND
PC570_P1_2  Q_CAP  22UF 16V 20% X6S  pkg C0805  page 285 : 1 = SW_P12V_PVCCIN_CPU1_FLT ; 2 = GND
PC571  Q_CAP  22UF 16V 20% X6S  pkg C0805  page 259 : 1 = SW_P3V3_AUX_FLT ; 2 = GND
PC571_P1_1  Q_CAP  22UF 16V 20% X6S  pkg C0805  page 285 : 1 = SW_P12V_PVCCIN_CPU1_FLT ; 2 = GND
PC572_P1_1  Q_CAP  100NF 50V 10% X7R  pkg C0402  page 285 : 1 = PVCCIN_CPU1 ; 2 = GND
PC574_P1_1  Q_CAP  1UF 16V 10% X6S  pkg C0402  page 285 : 1 = PVCCIN_CPU1 ; 2 = GND
PC575_P1_2  Q_CAP  22UF 4V 20% X6S  pkg C0805  page 285 : 1 = PVCCIN_CPU1 ; 2 = GND
PC576  Q_CAP  22UF 16V 20% X6S  pkg C0805  page 259 : 1 = SW_P3V3_AUX_FLT ; 2 = GND
PC576_P1_1  Q_CAP  22UF 4V 20% X6S  pkg C0805  page 285 : 1 = PVCCIN_CPU1 ; 2 = GND
PC577  Q_CAP  0.1UF 25V 10% X7R  pkg 0402  page 259 : 1 = SW_P3V3_AUX_FLT ; 2 = GND
PC577_P1_2  Q_CAP  22UF 4V 20% X6S  pkg C0805  page 285 : 1 = PVCCIN_CPU1 ; 2 = GND
PC578_P1_1  Q_CAP  22UF 4V 20% X6S  pkg C0805  page 285 : 1 = PVCCIN_CPU1 ; 2 = GND
PC579  Q_CAPP  270UF 16V 20% OSCON  pkg THLF  page 285 : 1 = SW_P12V_PVCCIN_CPU1_FLT ; 2 = GND
PC580  Q_CAPP  560UF 2.5V 20% OSCON  pkg THLF  page 285 : 1 = PVCCIN_CPU1 ; 2 = GND
PC581  Q_CAP  4.7UF 16V 10% X6S  pkg C0603  page 259 : 1 = P3V3_AUX_VDRV ; 2 = GND
PC582  Q_CAPP  270UF 16V 20% OSCON  pkg THLF  page 285 : 1 = SW_P12V_PVCCIN_CPU1_FLT ; 2 = GND
PC583  Q_CAPP  560UF 2.5V 20% OSCON  pkg THLF  page 285 : 1 = PVCCIN_CPU1 ; 2 = GND
PC585  Q_CAPP  270UF 16V 20% OSCON  pkg THLF  page 285 : 1 = SW_P12V_PVCCIN_CPU1_FLT ; 2 = GND
PC586  Q_CAPP  560UF 2.5V 20% OSCON  pkg THLF  page 285 : 1 = PVCCIN_CPU1 ; 2 = GND
PC587  Q_CAPP  330UF 2.5V +10/-35% EMPTY  pkg SMLF  page 285 : 1 = PVCCIN_CPU1 ; 2 = GND
PC588  Q_CAPP  270UF 16V 20% OSCON  pkg THLF  page 285 : 1 = SW_P12V_PVCCIN_CPU1_FLT ; 2 = GND
PC589  Q_CAPP  560UF 2.5V 20% OSCON  pkg THLF  page 285 : 1 = PVCCIN_CPU1 ; 2 = GND
PC590  Q_CAPP  330UF 2.5V +10/-35% EMPTY  pkg SMLF  page 285 : 1 = PVCCIN_CPU1 ; 2 = GND
